G04*
G04 #@! TF.GenerationSoftware,Altium Limited,Altium Designer,23.0.1 (38)*
G04*
G04 Layer_Color=16711935*
%FSLAX44Y44*%
%MOMM*%
G71*
G04*
G04 #@! TF.SameCoordinates,9A23C038-B079-480F-8166-AFFB5740F5AE*
G04*
G04*
G04 #@! TF.FilePolarity,Positive*
G04*
G01*
G75*
%ADD42C,0.0127*%
D42*
X0Y10450D02*
G03*
X10450Y0I10450J0D01*
G01*
X661530Y-40D02*
G03*
X671710Y10150I-10J10190D01*
G01*
X671740Y306700D02*
G03*
X660940Y317490I-10800J-10D01*
G01*
X10680Y317470D02*
G03*
X-20Y306760I10J-10710D01*
G01*
X10680Y317470D02*
X660940Y317490D01*
X10450Y0D02*
X661530Y-40D01*
X-20Y306760D02*
X0Y10450D01*
X671710Y10150D02*
X671740Y306700D01*
M02*
